# BASEBOARD_FAB2 (Tioga Pass) — schematic netlist excerpt (pin names and nets, part order shuffled) for the footprints in the layout excerpt that follows; sources: Cadence DE-HDL packaged netlist, KiCad conversion of Wiwynn_Tioga_Pass_MB.brd

R1F6  RES  1.00K 1% CHIP  pkg 0402  page 100 : A = M_G_VREF ; B = GND
R8A12  RES  475.0 1% CHIP  pkg 0603  page 237 : A = P1V8_PCH_STBY ; B = GND
R4E22  RES  68.1K 1% EMPTY  pkg 0402  page 202 : A = VR_PVCCIN_CPU0_PH1_OCSET ; B = GND

(kicad_pcb
	(version 20260206)
	(generator "pcbnew")
	(generator_version "10.0")
	(general
		(thickness 1.6)
		(legacy_teardrops no)
	)
	(paper "A4")
	(title_block
		(title "Wiwynn_Tioga_Pass_MB.brd")
		(comment 1 "Tioga Pass / footprints 2115-2117 of 4770")
	)
	(layers
		(0 "F.Cu" signal "TOP")
		(4 "In1.Cu" signal "L2GND")
		(6 "In2.Cu" signal "L3")
		(8 "In3.Cu" signal "L4GND")
		(10 "In4.Cu" signal "L5")
		(12 "In5.Cu" signal "L6GND")
		(14 "In6.Cu" signal "L7VCC")
		(16 "In7.Cu" signal "L8VCC")
		(18 "In8.Cu" signal "L9GND")
		(20 "In9.Cu" signal "L10")
		(22 "In10.Cu" signal "L11GND")
		(24 "In11.Cu" signal "L12")
		(26 "In12.Cu" signal "L13GND")
		(2 "B.Cu" signal "BOTTOM")
		(9 "F.Adhes" user "F.Adhesive")
		(11 "B.Adhes" user "B.Adhesive")
		(13 "F.Paste" user "Package Geometry/Pastemask Top")
		(15 "B.Paste" user "Package Geometry/Pastemask Bottom")
		(5 "F.SilkS" user "Ref Des/Silkscreen Top")
		(7 "B.SilkS" user "Ref Des/Silkscreen Bottom")
		(1 "F.Mask" user "Board Geometry/Soldermask Top")
		(3 "B.Mask" user "Board Geometry/Soldermask Bottom")
		(17 "Dwgs.User" user "User.Drawings")
		(19 "Cmts.User" user "User.Comments")
		(21 "Eco1.User" user "User.Eco1")
		(23 "Eco2.User" user "User.Eco2")
		(25 "Edge.Cuts" user "Board Geometry/Outline")
		(27 "Margin" user)
		(31 "F.CrtYd" user "Package Geometry/Place Bound Top")
		(29 "B.CrtYd" user "Package Geometry/Place Bound Bottom")
		(35 "F.Fab" user "Ref Des/Assembly Top")
		(33 "B.Fab" user "Ref Des/Assembly Bottom")
	)
	(footprint ""
		(layer "F.Cu")
		(at 404.03018 -145.085816 -90)
		(property "Reference" "R8A12"
			(at 0 0 270)
			(layer "F.SilkS")
			(hide yes)
			(effects
				(font
					(size 1.27 1.27)
				)
			)
		)
		(property "Value" ""
			(at 0 0 270)
			(layer "F.Fab")
			(effects
				(font
					(size 1.27 1.27)
				)
			)
		)
		(duplicate_pad_numbers_are_jumpers no)
		(fp_poly
			(pts
				(xy -0.4953 -0.2032) (xy 0.4953 -0.2032) (xy 0.4953 1.6002) (xy -0.4953 1.6002)
			)
			(stroke
				(width 0)
				(type default)
			)
			(fill no)
			(layer "F.CrtYd")
		)
		(fp_line
			(start -0.4953 1.6002)
			(end -0.4953 -0.2032)
			(stroke
				(width 0.1)
				(type default)
			)
			(layer "F.Fab")
		)
		(fp_line
			(start 0.4953 1.6002)
			(end -0.4953 1.6002)
			(stroke
				(width 0.1)
				(type default)
			)
			(layer "F.Fab")
		)
		(fp_line
			(start -0.4953 -0.2032)
			(end 0.4953 -0.2032)
			(stroke
				(width 0.1)
				(type default)
			)
			(layer "F.Fab")
		)
		(fp_line
			(start 0.4953 -0.2032)
			(end 0.4953 1.6002)
			(stroke
				(width 0.1)
				(type default)
			)
			(layer "F.Fab")
		)
		(pad "1" smd rect
			(at 0 0 270)
			(size 0.762 0.889)
			(layers "F.Cu" "F.Mask" "F.Paste")
			(net "P1V8_PCH_STBY")
		)
		(pad "2" smd rect
			(at 0 1.397 270)
			(size 0.762 0.889)
			(layers "F.Cu" "F.Mask" "F.Paste")
			(net "GND")
		)
		(zone
			(layer "F.Cu")
			(hatch none 0.5)
			(connect_pads
				(clearance 0)
			)
			(min_thickness 0.25)
			(keepout
				(tracks not_allowed)
				(vias allowed)
				(pads allowed)
				(copperpour not_allowed)
				(footprints allowed)
			)
			(placement
				(enabled no)
				(sheetname "")
			)
			(fill
				(thermal_gap 0.5)
				(thermal_bridge_width 0.5)
				(island_removal_mode 0)
			)
			(polygon
				(pts
					(xy 403.07768 -145.466816) (xy 403.07768 -144.704816) (xy 403.58568 -144.704816) (xy 403.58568 -145.466816)
				)
			)
		)
		(zone
			(layer "F.Cu")
			(hatch none 0.5)
			(connect_pads
				(clearance 0)
			)
			(min_thickness 0.25)
			(keepout
				(tracks allowed)
				(vias not_allowed)
				(pads allowed)
				(copperpour not_allowed)
				(footprints allowed)
			)
			(placement
				(enabled no)
				(sheetname "")
			)
			(fill
				(thermal_gap 0.5)
				(thermal_bridge_width 0.5)
				(island_removal_mode 0)
			)
			(polygon
				(pts
					(xy 403.07768 -144.704816) (xy 403.58568 -144.704816) (xy 403.58568 -145.466816) (xy 403.07768 -145.466816)
				)
			)
		)
	)
	(footprint ""
		(layer "F.Cu")
		(at 29.807916 -22.105366 180)
		(property "Reference" "R1F6"
			(at 0 0 180)
			(layer "F.SilkS")
			(hide yes)
			(effects
				(font
					(size 1.27 1.27)
				)
			)
		)
		(property "Value" ""
			(at 0 0 180)
			(layer "F.Fab")
			(effects
				(font
					(size 1.27 1.27)
				)
			)
		)
		(duplicate_pad_numbers_are_jumpers no)
		(fp_poly
			(pts
				(xy -0.2794 -0.1016) (xy 0.2794 -0.1016) (xy 0.2794 0.9906) (xy -0.2794 0.9906)
			)
			(stroke
				(width 0)
				(type default)
			)
			(fill no)
			(layer "F.CrtYd")
		)
		(fp_line
			(start 0.2794 0.9906)
			(end 0.2794 -0.1016)
			(stroke
				(width 0.1)
				(type default)
			)
			(layer "F.Fab")
		)
		(fp_line
			(start 0.2794 -0.1016)
			(end -0.2794 -0.1016)
			(stroke
				(width 0.1)
				(type default)
			)
			(layer "F.Fab")
		)
		(fp_line
			(start -0.2794 0.9906)
			(end 0.2794 0.9906)
			(stroke
				(width 0.1)
				(type default)
			)
			(layer "F.Fab")
		)
		(fp_line
			(start -0.2794 -0.1016)
			(end -0.2794 0.9906)
			(stroke
				(width 0.1)
				(type default)
			)
			(layer "F.Fab")
		)
		(pad "1" smd rect
			(at 0 0 180)
			(size 0.508 0.508)
			(layers "F.Cu" "F.Mask" "F.Paste")
			(net "M_G_VREF")
		)
		(pad "2" smd rect
			(at 0 0.889 180)
			(size 0.508 0.508)
			(layers "F.Cu" "F.Mask" "F.Paste")
			(net "GND")
		)
		(zone
			(layer "F.Cu")
			(hatch none 0.5)
			(connect_pads
				(clearance 0)
			)
			(min_thickness 0.25)
			(keepout
				(tracks not_allowed)
				(vias allowed)
				(pads allowed)
				(copperpour not_allowed)
				(footprints allowed)
			)
			(placement
				(enabled no)
				(sheetname "")
			)
			(fill
				(thermal_gap 0.5)
				(thermal_bridge_width 0.5)
				(island_removal_mode 0)
			)
			(polygon
				(pts
					(xy 30.061916 -22.740366) (xy 29.553916 -22.740366) (xy 29.553916 -22.359366) (xy 30.061916 -22.359366)
				)
			)
		)
		(zone
			(layer "F.Cu")
			(hatch none 0.5)
			(connect_pads
				(clearance 0)
			)
			(min_thickness 0.25)
			(keepout
				(tracks allowed)
				(vias not_allowed)
				(pads allowed)
				(copperpour not_allowed)
				(footprints allowed)
			)
			(placement
				(enabled no)
				(sheetname "")
			)
			(fill
				(thermal_gap 0.5)
				(thermal_bridge_width 0.5)
				(island_removal_mode 0)
			)
			(polygon
				(pts
					(xy 30.061916 -22.359366) (xy 29.553916 -22.359366) (xy 29.553916 -22.740366) (xy 30.061916 -22.740366)
				)
			)
		)
	)
	(footprint ""
		(layer "F.Cu")
		(at 193.6242 -55.0164)
		(property "Reference" "R4E22"
			(at 0 0 0)
			(layer "F.SilkS")
			(hide yes)
			(effects
				(font
					(size 1.27 1.27)
				)
			)
		)
		(property "Value" ""
			(at 0 0 0)
			(layer "F.Fab")
			(effects
				(font
					(size 1.27 1.27)
				)
			)
		)
		(duplicate_pad_numbers_are_jumpers no)
		(fp_poly
			(pts
				(xy -0.2794 -0.1016) (xy 0.2794 -0.1016) (xy 0.2794 0.9906) (xy -0.2794 0.9906)
			)
			(stroke
				(width 0)
				(type default)
			)
			(fill no)
			(layer "F.CrtYd")
		)
		(fp_line
			(start -0.2794 -0.1016)
			(end -0.2794 0.9906)
			(stroke
				(width 0.1)
				(type default)
			)
			(layer "F.Fab")
		)
		(fp_line
			(start -0.2794 0.9906)
			(end 0.2794 0.9906)
			(stroke
				(width 0.1)
				(type default)
			)
			(layer "F.Fab")
		)
		(fp_line
			(start 0.2794 -0.1016)
			(end -0.2794 -0.1016)
			(stroke
				(width 0.1)
				(type default)
			)
			(layer "F.Fab")
		)
		(fp_line
			(start 0.2794 0.9906)
			(end 0.2794 -0.1016)
			(stroke
				(width 0.1)
				(type default)
			)
			(layer "F.Fab")
		)
		(pad "1" smd rect
			(at 0 0)
			(size 0.508 0.508)
			(layers "F.Cu" "F.Mask" "F.Paste")
			(net "VR_PVCCIN_CPU0_PH1_OCSET")
		)
		(pad "2" smd rect
			(at 0 0.889)
			(size 0.508 0.508)
			(layers "F.Cu" "F.Mask" "F.Paste")
			(net "GND")
		)
		(zone
			(layer "F.Cu")
			(hatch none 0.5)
			(connect_pads
				(clearance 0)
			)
			(min_thickness 0.25)
			(keepout
				(tracks allowed)
				(vias not_allowed)
				(pads allowed)
				(copperpour not_allowed)
				(footprints allowed)
			)
			(placement
				(enabled no)
				(sheetname "")
			)
			(fill
				(thermal_gap 0.5)
				(thermal_bridge_width 0.5)
				(island_removal_mode 0)
			)
			(polygon
				(pts
					(xy 193.3702 -54.7624) (xy 193.8782 -54.7624) (xy 193.8782 -54.3814) (xy 193.3702 -54.3814)
				)
			)
		)
		(zone
			(layer "F.Cu")
			(hatch none 0.5)
			(connect_pads
				(clearance 0)
			)
			(min_thickness 0.25)
			(keepout
				(tracks not_allowed)
				(vias allowed)
				(pads allowed)
				(copperpour not_allowed)
				(footprints allowed)
			)
			(placement
				(enabled no)
				(sheetname "")
			)
			(fill
				(thermal_gap 0.5)
				(thermal_bridge_width 0.5)
				(island_removal_mode 0)
			)
			(polygon
				(pts
					(xy 193.3702 -54.3814) (xy 193.8782 -54.3814) (xy 193.8782 -54.7624) (xy 193.3702 -54.7624)
				)
			)
		)
	)
)
